FILE_TYPE = CONNECTIVITY;
{Allegro Design Entry HDL 17.2-2016 S081 (4005846) 1/11/2022}
"PAGE_NUMBER" = 57;
0"NC";
1"M_G_CPU1_SA_CA<6:0>";
2"M_G_CPU1_SA_CS_N<3:0>";
3"M_G_CPU1_SA_DQS_DN<9:0>";
4"M_G_CPU1_SA_DQS_DP<9:0>";
5"M_G_CPU1_SB_CA<6:0>";
6"M_G_CPU1_SB_CS_N<3:0>";
7"M_G_CPU1_SB_DQS_DN<9:0>";
8"M_G_CPU1_SB_DQS_DP<9:0>";
9"M_G_CPU1_SB_CB<7:0>";
10"M_G_CPU1_SB_DQ<31:0>";
11"M_G_CPU1_SA_CB<7:0>";
12"M_G_CPU1_SA_DQ<31:0>";
13"M_G_CPU1_CLK_DP<1:0>";
14"M_G_CPU1_CLK_DN<1:0>";
15"M_G_CPU1_CLK_DN<0>";
16"M_G_CPU1_CLK_DN<1>";
17"M_G_CPU1_CLK_DP<1>";
18"M_G_CPU1_CLK_DP<0>";
19"M_G_CPU1_SA_DQ<31>";
20"M_G_CPU1_SA_DQ<30>";
21"M_G_CPU1_SA_DQ<29>";
22"M_G_CPU1_SA_DQ<28>";
23"M_G_CPU1_SA_DQ<27>";
24"M_G_CPU1_SA_DQ<26>";
25"M_G_CPU1_SA_DQ<25>";
26"M_G_CPU1_SA_DQ<24>";
27"M_G_CPU1_SA_DQ<23>";
28"M_G_CPU1_SA_DQ<22>";
29"M_G_CPU1_SA_DQ<21>";
30"M_G_CPU1_SA_DQ<20>";
31"M_G_CPU1_SA_DQ<19>";
32"M_G_CPU1_SA_DQ<18>";
33"M_G_CPU1_SA_DQ<17>";
34"M_G_CPU1_SA_DQ<16>";
35"M_G_CPU1_SA_DQ<15>";
36"M_G_CPU1_SA_DQ<14>";
37"M_G_CPU1_SA_DQ<13>";
38"M_G_CPU1_SA_DQ<12>";
39"M_G_CPU1_SA_DQ<11>";
40"M_G_CPU1_SA_DQ<10>";
41"M_G_CPU1_SA_DQ<9>";
42"M_G_CPU1_SA_DQ<8>";
43"M_G_CPU1_SA_DQ<7>";
44"M_G_CPU1_SA_DQ<6>";
45"M_G_CPU1_SA_DQ<5>";
46"M_G_CPU1_SA_DQ<4>";
47"M_G_CPU1_SA_DQ<3>";
48"M_G_CPU1_SA_DQ<2>";
49"M_G_CPU1_SA_DQ<1>";
50"M_G_CPU1_SA_DQ<0>";
51"M_G_CPU1_SA_CB<7>";
52"M_G_CPU1_SA_CB<6>";
53"M_G_CPU1_SA_CB<5>";
54"M_G_CPU1_SA_CB<4>";
55"M_G_CPU1_SA_CB<3>";
56"M_G_CPU1_SA_CB<2>";
57"M_G_CPU1_SA_CB<1>";
58"M_G_CPU1_SA_CB<0>";
59"M_G_CPU1_SB_DQ<31>";
60"M_G_CPU1_SB_DQ<30>";
61"M_G_CPU1_SB_DQ<29>";
62"M_G_CPU1_SB_DQ<28>";
63"M_G_CPU1_SB_DQ<27>";
64"M_G_CPU1_SB_DQ<26>";
65"M_G_CPU1_SB_DQ<25>";
66"M_G_CPU1_SB_DQ<24>";
67"M_G_CPU1_SB_DQ<23>";
68"M_G_CPU1_SB_DQ<22>";
69"M_G_CPU1_SB_DQ<21>";
70"M_G_CPU1_SB_DQ<20>";
71"M_G_CPU1_SB_DQ<19>";
72"M_G_CPU1_SB_DQ<18>";
73"M_G_CPU1_SB_DQ<17>";
74"M_G_CPU1_SB_DQ<16>";
75"M_G_CPU1_SB_DQ<15>";
76"M_G_CPU1_SB_DQ<14>";
77"M_G_CPU1_SB_DQ<13>";
78"M_G_CPU1_SB_DQ<12>";
79"M_G_CPU1_SB_DQ<11>";
80"M_G_CPU1_SB_DQ<10>";
81"M_G_CPU1_SB_DQ<9>";
82"M_G_CPU1_SB_DQ<8>";
83"M_G_CPU1_SB_DQ<7>";
84"M_G_CPU1_SB_DQ<6>";
85"M_G_CPU1_SB_DQ<5>";
86"M_G_CPU1_SB_DQ<4>";
87"M_G_CPU1_SB_DQ<3>";
88"M_G_CPU1_SB_DQ<2>";
89"M_G_CPU1_SB_DQ<1>";
90"M_G_CPU1_SB_DQ<0>";
91"M_G_CPU1_SB_CB<7>";
92"M_G_CPU1_SB_CB<6>";
93"M_G_CPU1_SB_CB<5>";
94"M_G_CPU1_SB_CB<4>";
95"M_G_CPU1_SB_CB<3>";
96"M_G_CPU1_SB_CB<2>";
97"M_G_CPU1_SB_CB<1>";
98"M_G_CPU1_SB_CB<0>";
99"M_G_CPU1_SB_PAR";
100"M_G_CPU1_SB_DQS_DP<0>";
101"M_G_CPU1_SB_DQS_DP<1>";
102"M_G_CPU1_SB_DQS_DP<2>";
103"M_G_CPU1_SB_DQS_DP<3>";
104"M_G_CPU1_SB_DQS_DP<4>";
105"M_G_CPU1_SB_DQS_DP<5>";
106"M_G_CPU1_SB_DQS_DP<6>";
107"M_G_CPU1_SB_DQS_DP<7>";
108"M_G_CPU1_SB_DQS_DP<8>";
109"M_G_CPU1_SB_DQS_DP<9>";
110"M_G_CPU1_SB_DQS_DN<0>";
111"M_G_CPU1_SB_DQS_DN<1>";
112"M_G_CPU1_SB_DQS_DN<2>";
113"M_G_CPU1_SB_DQS_DN<3>";
114"M_G_CPU1_SB_DQS_DN<4>";
115"M_G_CPU1_SB_DQS_DN<5>";
116"M_G_CPU1_SB_DQS_DN<6>";
117"M_G_CPU1_SB_DQS_DN<7>";
118"M_G_CPU1_SB_DQS_DN<8>";
119"M_G_CPU1_SB_DQS_DN<9>";
120"M_G_CPU1_SB_CS_N<0>";
121"M_G_CPU1_SB_CS_N<1>";
122"M_G_CPU1_SB_CS_N<2>";
123"M_G_CPU1_SB_CS_N<3>";
124"M_G_CPU1_SB_CA<0>";
125"M_G_CPU1_SB_CA<1>";
126"M_G_CPU1_SB_CA<2>";
127"M_G_CPU1_SB_CA<3>";
128"M_G_CPU1_SB_CA<4>";
129"M_G_CPU1_SB_CA<5>";
130"M_G_CPU1_SB_CA<6>";
131"M_G_CPU1_SA_PAR";
132"M_G_CPU1_SA_DQS_DP<0>";
133"M_G_CPU1_SA_DQS_DP<1>";
134"M_G_CPU1_SA_DQS_DP<2>";
135"M_G_CPU1_SA_DQS_DP<3>";
136"M_G_CPU1_SA_DQS_DP<4>";
137"M_G_CPU1_SA_DQS_DP<5>";
138"M_G_CPU1_SA_DQS_DP<6>";
139"M_G_CPU1_SA_DQS_DP<7>";
140"M_G_CPU1_SA_DQS_DP<8>";
141"M_G_CPU1_SA_DQS_DP<9>";
142"M_G_CPU1_SA_DQS_DN<0>";
143"M_G_CPU1_SA_DQS_DN<1>";
144"M_G_CPU1_SA_DQS_DN<2>";
145"M_G_CPU1_SA_DQS_DN<3>";
146"M_G_CPU1_SA_DQS_DN<4>";
147"M_G_CPU1_SA_DQS_DN<5>";
148"M_G_CPU1_SA_DQS_DN<6>";
149"M_G_CPU1_SA_DQS_DN<7>";
150"M_G_CPU1_SA_DQS_DN<8>";
151"M_G_CPU1_SA_DQS_DN<9>";
152"M_G_CPU1_SA_CS_N<0>";
153"M_G_CPU1_SA_CS_N<1>";
154"M_G_CPU1_SA_CS_N<2>";
155"M_G_CPU1_SA_CS_N<3>";
156"M_G_CPU1_SA_CA<0>";
157"M_G_CPU1_SA_CA<1>";
158"M_G_CPU1_SA_CA<2>";
159"M_G_CPU1_SA_CA<3>";
160"M_G_CPU1_SA_CA<4>";
161"M_G_CPU1_SA_CA<5>";
162"M_G_CPU1_SA_CA<6>";
163"M_G_CPU1_SB_RSP<0>";
164"M_G_CPU1_SB_RSP<1>";
165"M_G_CPU1_SA_RSP<0>";
166"M_G_CPU1_SA_RSP<1>";
167"M_G_CPU1_ALERT_N";
%"TAP"
"1","(-1200,150)","2","standard","I10";
;
CDS_LIB"standard"
BODY_TYPE"PLUMBING"
HDL_TAP"TRUE";
"B \NAC \NWC"9;
"S \NAC"
BN"1"97;
%"TAP"
"1","(2225,750)","0","standard","I100";
;
CDS_LIB"standard"
BODY_TYPE"PLUMBING"
HDL_TAP"TRUE";
"B \NAC \NWC"2;
"S \NAC"
BN"3"155;
%"TAP"
"1","(2225,650)","0","standard","I101";
;
CDS_LIB"standard"
BODY_TYPE"PLUMBING"
HDL_TAP"TRUE";
"B \NAC \NWC"2;
"S \NAC"
BN"1"153;
%"TAP"
"1","(2225,950)","0","standard","I102";
;
CDS_LIB"standard"
BODY_TYPE"PLUMBING"
HDL_TAP"TRUE";
"B \NAC \NWC"5;
"S \NAC"
BN"0"124;
%"TAP"
"1","(2225,1000)","0","standard","I103";
;
CDS_LIB"standard"
BODY_TYPE"PLUMBING"
HDL_TAP"TRUE";
"B \NAC \NWC"5;
"S \NAC"
BN"1"125;
%"TAP"
"1","(2225,1050)","0","standard","I104";
;
CDS_LIB"standard"
BODY_TYPE"PLUMBING"
HDL_TAP"TRUE";
"B \NAC \NWC"5;
"S \NAC"
BN"2"126;
%"TAP"
"1","(2225,1100)","0","standard","I105";
;
CDS_LIB"standard"
BODY_TYPE"PLUMBING"
HDL_TAP"TRUE";
"B \NAC \NWC"5;
"S \NAC"
BN"3"127;
%"TAP"
"1","(2225,1150)","0","standard","I106";
;
CDS_LIB"standard"
BODY_TYPE"PLUMBING"
HDL_TAP"TRUE";
"B \NAC \NWC"5;
"S \NAC"
BN"4"128;
%"TAP"
"1","(2225,1200)","0","standard","I107";
;
CDS_LIB"standard"
BODY_TYPE"PLUMBING"
HDL_TAP"TRUE";
"B \NAC \NWC"5;
"S \NAC"
BN"5"129;
%"TAP"
"1","(2225,1250)","0","standard","I108";
;
CDS_LIB"standard"
BODY_TYPE"PLUMBING"
HDL_TAP"TRUE";
"B \NAC \NWC"5;
"S \NAC"
BN"6"130;
%"TAP"
"1","(2225,1450)","0","standard","I109";
;
CDS_LIB"standard"
BODY_TYPE"PLUMBING"
HDL_TAP"TRUE";
"B \NAC \NWC"1;
"S \NAC"
BN"0"156;
%"TAP"
"1","(-1200,200)","2","standard","I11";
;
CDS_LIB"standard"
BODY_TYPE"PLUMBING"
HDL_TAP"TRUE";
"B \NAC \NWC"9;
"S \NAC"
BN"2"96;
%"TAP"
"1","(2225,1500)","0","standard","I110";
;
CDS_LIB"standard"
BODY_TYPE"PLUMBING"
HDL_TAP"TRUE";
"B \NAC \NWC"1;
"S \NAC"
BN"1"157;
%"TAP"
"1","(2225,1550)","0","standard","I111";
;
CDS_LIB"standard"
BODY_TYPE"PLUMBING"
HDL_TAP"TRUE";
"B \NAC \NWC"1;
"S \NAC"
BN"2"158;
%"TAP"
"1","(2225,1600)","0","standard","I112";
;
CDS_LIB"standard"
BODY_TYPE"PLUMBING"
HDL_TAP"TRUE";
"B \NAC \NWC"1;
"S \NAC"
BN"3"159;
%"TAP"
"1","(2225,1650)","0","standard","I113";
;
CDS_LIB"standard"
BODY_TYPE"PLUMBING"
HDL_TAP"TRUE";
"B \NAC \NWC"1;
"S \NAC"
BN"4"160;
%"TAP"
"1","(2225,1700)","0","standard","I114";
;
CDS_LIB"standard"
BODY_TYPE"PLUMBING"
HDL_TAP"TRUE";
"B \NAC \NWC"1;
"S \NAC"
BN"5"161;
%"TAP"
"1","(2225,1750)","0","standard","I115";
;
CDS_LIB"standard"
BODY_TYPE"PLUMBING"
HDL_TAP"TRUE";
"B \NAC \NWC"1;
"S \NAC"
BN"6"162;
%"TAP"
"1","(2225,1900)","0","standard","I116";
;
CDS_LIB"standard"
BODY_TYPE"PLUMBING"
HDL_TAP"TRUE";
"B \NAC \NWC"7;
"S \NAC"
BN"0"110;
%"TAP"
"1","(2225,1950)","0","standard","I117";
;
CDS_LIB"standard"
BODY_TYPE"PLUMBING"
HDL_TAP"TRUE";
"B \NAC \NWC"7;
"S \NAC"
BN"1"111;
%"TAP"
"1","(2225,2000)","0","standard","I118";
;
CDS_LIB"standard"
BODY_TYPE"PLUMBING"
HDL_TAP"TRUE";
"B \NAC \NWC"7;
"S \NAC"
BN"2"112;
%"TAP"
"1","(2225,2050)","0","standard","I119";
;
CDS_LIB"standard"
BODY_TYPE"PLUMBING"
HDL_TAP"TRUE";
"B \NAC \NWC"7;
"S \NAC"
BN"3"113;
%"TAP"
"1","(-1200,250)","2","standard","I12";
;
CDS_LIB"standard"
BODY_TYPE"PLUMBING"
HDL_TAP"TRUE";
"B \NAC \NWC"9;
"S \NAC"
BN"3"95;
%"TAP"
"1","(2225,2100)","0","standard","I120";
;
CDS_LIB"standard"
BODY_TYPE"PLUMBING"
HDL_TAP"TRUE";
"B \NAC \NWC"7;
"S \NAC"
BN"4"114;
%"TAP"
"1","(2225,2150)","0","standard","I121";
;
CDS_LIB"standard"
BODY_TYPE"PLUMBING"
HDL_TAP"TRUE";
"B \NAC \NWC"7;
"S \NAC"
BN"5"115;
%"TAP"
"1","(2225,2200)","0","standard","I122";
;
CDS_LIB"standard"
BODY_TYPE"PLUMBING"
HDL_TAP"TRUE";
"B \NAC \NWC"7;
"S \NAC"
BN"6"116;
%"TAP"
"1","(2225,2250)","0","standard","I123";
;
CDS_LIB"standard"
BODY_TYPE"PLUMBING"
HDL_TAP"TRUE";
"B \NAC \NWC"7;
"S \NAC"
BN"7"117;
%"TAP"
"1","(2225,2300)","0","standard","I124";
;
CDS_LIB"standard"
BODY_TYPE"PLUMBING"
HDL_TAP"TRUE";
"B \NAC \NWC"7;
"S \NAC"
BN"8"118;
%"TAP"
"1","(2225,2450)","0","standard","I125";
;
CDS_LIB"standard"
BODY_TYPE"PLUMBING"
HDL_TAP"TRUE";
"B \NAC \NWC"8;
"S \NAC"
BN"0"100;
%"TAP"
"1","(2225,2500)","0","standard","I126";
;
CDS_LIB"standard"
BODY_TYPE"PLUMBING"
HDL_TAP"TRUE";
"B \NAC \NWC"8;
"S \NAC"
BN"1"101;
%"TAP"
"1","(2225,2550)","0","standard","I127";
;
CDS_LIB"standard"
BODY_TYPE"PLUMBING"
HDL_TAP"TRUE";
"B \NAC \NWC"8;
"S \NAC"
BN"2"102;
%"TAP"
"1","(2225,2350)","0","standard","I128";
;
CDS_LIB"standard"
BODY_TYPE"PLUMBING"
HDL_TAP"TRUE";
"B \NAC \NWC"7;
"S \NAC"
BN"9"119;
%"TAP"
"1","(2225,2600)","0","standard","I129";
;
CDS_LIB"standard"
BODY_TYPE"PLUMBING"
HDL_TAP"TRUE";
"B \NAC \NWC"8;
"S \NAC"
BN"3"103;
%"TAP"
"1","(-1200,300)","2","standard","I13";
;
CDS_LIB"standard"
BODY_TYPE"PLUMBING"
HDL_TAP"TRUE";
"B \NAC \NWC"9;
"S \NAC"
BN"4"94;
%"TAP"
"1","(2225,2650)","0","standard","I130";
;
CDS_LIB"standard"
BODY_TYPE"PLUMBING"
HDL_TAP"TRUE";
"B \NAC \NWC"8;
"S \NAC"
BN"4"104;
%"TAP"
"1","(2225,2750)","0","standard","I131";
;
CDS_LIB"standard"
BODY_TYPE"PLUMBING"
HDL_TAP"TRUE";
"B \NAC \NWC"8;
"S \NAC"
BN"6"106;
%"TAP"
"1","(2225,2800)","0","standard","I132";
;
CDS_LIB"standard"
BODY_TYPE"PLUMBING"
HDL_TAP"TRUE";
"B \NAC \NWC"8;
"S \NAC"
BN"7"107;
%"TAP"
"1","(2225,2700)","0","standard","I133";
;
CDS_LIB"standard"
BODY_TYPE"PLUMBING"
HDL_TAP"TRUE";
"B \NAC \NWC"8;
"S \NAC"
BN"5"105;
%"TAP"
"1","(2225,2850)","0","standard","I134";
;
CDS_LIB"standard"
BODY_TYPE"PLUMBING"
HDL_TAP"TRUE";
"B \NAC \NWC"8;
"S \NAC"
BN"8"108;
%"TAP"
"1","(2225,2900)","0","standard","I135";
;
CDS_LIB"standard"
BODY_TYPE"PLUMBING"
HDL_TAP"TRUE";
"B \NAC \NWC"8;
"S \NAC"
BN"9"109;
%"TAP"
"1","(2225,3050)","0","standard","I136";
;
CDS_LIB"standard"
BODY_TYPE"PLUMBING"
HDL_TAP"TRUE";
"B \NAC \NWC"3;
"S \NAC"
BN"0"142;
%"TAP"
"1","(2225,3100)","0","standard","I137";
;
CDS_LIB"standard"
BODY_TYPE"PLUMBING"
HDL_TAP"TRUE";
"B \NAC \NWC"3;
"S \NAC"
BN"1"143;
%"TAP"
"1","(2225,3150)","0","standard","I138";
;
CDS_LIB"standard"
BODY_TYPE"PLUMBING"
HDL_TAP"TRUE";
"B \NAC \NWC"3;
"S \NAC"
BN"2"144;
%"TAP"
"1","(2225,3200)","0","standard","I139";
;
CDS_LIB"standard"
BODY_TYPE"PLUMBING"
HDL_TAP"TRUE";
"B \NAC \NWC"3;
"S \NAC"
BN"3"145;
%"TAP"
"1","(-1200,350)","2","standard","I14";
;
CDS_LIB"standard"
BODY_TYPE"PLUMBING"
HDL_TAP"TRUE";
"B \NAC \NWC"9;
"S \NAC"
BN"5"93;
%"TAP"
"1","(2225,3250)","0","standard","I140";
;
CDS_LIB"standard"
BODY_TYPE"PLUMBING"
HDL_TAP"TRUE";
"B \NAC \NWC"3;
"S \NAC"
BN"4"146;
%"TAP"
"1","(2225,3300)","0","standard","I141";
;
CDS_LIB"standard"
BODY_TYPE"PLUMBING"
HDL_TAP"TRUE";
"B \NAC \NWC"3;
"S \NAC"
BN"5"147;
%"TAP"
"1","(2225,3500)","0","standard","I142";
;
CDS_LIB"standard"
BODY_TYPE"PLUMBING"
HDL_TAP"TRUE";
"B \NAC \NWC"3;
"S \NAC"
BN"9"151;
%"TAP"
"1","(2225,3450)","0","standard","I143";
;
CDS_LIB"standard"
BODY_TYPE"PLUMBING"
HDL_TAP"TRUE";
"B \NAC \NWC"3;
"S \NAC"
BN"8"150;
%"TAP"
"1","(2225,3400)","0","standard","I144";
;
CDS_LIB"standard"
BODY_TYPE"PLUMBING"
HDL_TAP"TRUE";
"B \NAC \NWC"3;
"S \NAC"
BN"7"149;
%"TAP"
"1","(2225,3350)","0","standard","I145";
;
CDS_LIB"standard"
BODY_TYPE"PLUMBING"
HDL_TAP"TRUE";
"B \NAC \NWC"3;
"S \NAC"
BN"6"148;
%"TAP"
"1","(2225,3600)","0","standard","I146";
;
CDS_LIB"standard"
BODY_TYPE"PLUMBING"
HDL_TAP"TRUE";
"B \NAC \NWC"4;
"S \NAC"
BN"0"132;
%"TAP"
"1","(2225,3650)","0","standard","I147";
;
CDS_LIB"standard"
BODY_TYPE"PLUMBING"
HDL_TAP"TRUE";
"B \NAC \NWC"4;
"S \NAC"
BN"1"133;
%"TAP"
"1","(2225,3700)","0","standard","I148";
;
CDS_LIB"standard"
BODY_TYPE"PLUMBING"
HDL_TAP"TRUE";
"B \NAC \NWC"4;
"S \NAC"
BN"2"134;
%"TAP"
"1","(2225,3750)","0","standard","I149";
;
CDS_LIB"standard"
BODY_TYPE"PLUMBING"
HDL_TAP"TRUE";
"B \NAC \NWC"4;
"S \NAC"
BN"3"135;
%"TAP"
"1","(-1200,400)","2","standard","I15";
;
CDS_LIB"standard"
BODY_TYPE"PLUMBING"
HDL_TAP"TRUE";
"B \NAC \NWC"9;
"S \NAC"
BN"6"92;
%"TAP"
"1","(2225,3800)","0","standard","I150";
;
CDS_LIB"standard"
BODY_TYPE"PLUMBING"
HDL_TAP"TRUE";
"B \NAC \NWC"4;
"S \NAC"
BN"4"136;
%"TAP"
"1","(2225,3850)","0","standard","I151";
;
CDS_LIB"standard"
BODY_TYPE"PLUMBING"
HDL_TAP"TRUE";
"B \NAC \NWC"4;
"S \NAC"
BN"5"137;
%"TAP"
"1","(2225,3900)","0","standard","I152";
;
CDS_LIB"standard"
BODY_TYPE"PLUMBING"
HDL_TAP"TRUE";
"B \NAC \NWC"4;
"S \NAC"
BN"6"138;
%"TAP"
"1","(2225,3950)","0","standard","I153";
;
CDS_LIB"standard"
BODY_TYPE"PLUMBING"
HDL_TAP"TRUE";
"B \NAC \NWC"4;
"S \NAC"
BN"7"139;
%"TAP"
"1","(2225,4000)","0","standard","I154";
;
CDS_LIB"standard"
BODY_TYPE"PLUMBING"
HDL_TAP"TRUE";
"B \NAC \NWC"4;
"S \NAC"
BN"8"140;
%"TAP"
"1","(2225,4050)","0","standard","I155";
;
CDS_LIB"standard"
BODY_TYPE"PLUMBING"
HDL_TAP"TRUE";
"B \NAC \NWC"4;
"S \NAC"
BN"9"141;
%"TAP"
"1","(-1200,450)","2","standard","I16";
;
CDS_LIB"standard"
BODY_TYPE"PLUMBING"
HDL_TAP"TRUE";
"B \NAC \NWC"9;
"S \NAC"
BN"7"91;
%"SOCKET4677_AZIF0045P001C01CS"
"14","(525,1950)","0","pure_quanta","I168";
;
PART_NUMBER"DGA^7000023"
PART_TYPE"SMLF"
MATERIAL"IO"
VALUE"SOCKET4677_AZIF0045-P001C01CS"
$LOCATION"U1"
CDS_LIB"pure_quanta"
NEEDS_NO_SIZE"TRUE"
CDS_LMAN_SYM_OUTLINE"-1100,2250,1050,-2250"
CDS_LOCATION"U1"
$SEC"14"
CDS_SEC"14";
"DDR6_SB_PAR"
$PN"EB42"99;
"DDR6_SB_ECC0"
$PN"DU35"98;
"DDR6_SB_ECC1"
$PN"DV34"97;
"DDR6_SB_ECC2"
$PN"EA35"96;
"DDR6_SB_ECC3"
$PN"DY34"95;
"DDR6_SB_ECC4"
$PN"DV38"94;
"DDR6_SB_ECC5"
$PN"DU37"93;
"DDR6_SB_ECC6"
$PN"DY38"92;
"DDR6_SB_ECC7"
$PN"EA37"91;
"DDR6_SB_DQS_DP0"
$PN"DL33"100;
"DDR6_SB_DQS_DP1"
$PN"DL27"101;
"DDR6_SB_DQS_DP2"
$PN"DT24"102;
"DDR6_SB_DQS_DP3"
$PN"EN7"103;
"DDR6_SB_DQS_DP4"
$PN"DY36"104;
"DDR6_SB_DQS_DP5"
$PN"DN33"105;
"DDR6_SB_DQS_DP6"
$PN"DR27"106;
"DDR6_SB_DQS_DP7"
$PN"DY24"107;
"DDR6_SB_DQS_DP8"
$PN"EN5"108;
"DDR6_SB_DQS_DP9"
$PN"DT36"109;
"DDR6_SB_DQS_DN0 \B"
$PN"DJ33"110;
"DDR6_SB_DQS_DN1 \B"
$PN"DJ27"111;
"DDR6_SB_DQS_DN2 \B"
$PN"DV24"112;
"DDR6_SB_DQS_DN3 \B"
$PN"EP6"113;
"DDR6_SB_DQS_DN4 \B"
$PN"EB36"114;
"DDR6_SB_DQS_DN5 \B"
$PN"DR33"115;
"DDR6_SB_DQS_DN6 \B"
$PN"DN27"116;
"DDR6_SB_DQS_DN7 \B"
$PN"EB24"117;
"DDR6_SB_DQS_DN8 \B"
$PN"EM6"118;
"DDR6_SB_DQS_DN9 \B"
$PN"DV36"119;
"DDR6_SB_DQ0"
$PN"DL35"90;
"DDR6_SB_DQ1"
$PN"DK34"89;
"DDR6_SB_DQ2"
$PN"DN35"88;
"DDR6_SB_DQ3"
$PN"DP34"87;
"DDR6_SB_DQ4"
$PN"DK32"86;
"DDR6_SB_DQ5"
$PN"DL31"85;
"DDR6_SB_DQ6"
$PN"DP32"84;
"DDR6_SB_DQ7"
$PN"DN31"83;
"DDR6_SB_DQ8"
$PN"DN29"82;
"DDR6_SB_DQ9"
$PN"DK28"81;
"DDR6_SB_DQ10"
$PN"DL29"80;
"DDR6_SB_DQ11"
$PN"DP28"79;
"DDR6_SB_DQ12"
$PN"DK26"78;
"DDR6_SB_DQ13"
$PN"DL25"77;
"DDR6_SB_DQ14"
$PN"DP26"76;
"DDR6_SB_DQ15"
$PN"DN25"75;
"DDR6_SB_DQ16"
$PN"DV26"74;
"DDR6_SB_DQ17"
$PN"DU25"73;
"DDR6_SB_DQ18"
$PN"DY26"72;
"DDR6_SB_DQ19"
$PN"EA25"71;
"DDR6_SB_DQ20"
$PN"DU23"70;
"DDR6_SB_DQ21"
$PN"DV22"69;
"DDR6_SB_DQ22"
$PN"EA23"68;
"DDR6_SB_DQ23"
$PN"DY22"67;
"DDR6_SB_DQ24"
$PN"EK8"66;
"DDR6_SB_DQ25"
$PN"EH8"65;
"DDR6_SB_DQ26"
$PN"EP8"64;
"DDR6_SB_DQ27"
$PN"ET8"63;
"DDR6_SB_DQ28"
$PN"EK6"62;
"DDR6_SB_DQ29"
$PN"EJ5"61;
"DDR6_SB_DQ30"
$PN"EP4"60;
"DDR6_SB_DQ31"
$PN"EM4"59;
"DDR6_SB_CS_N0 \B"
$PN"EA41"120;
"DDR6_SB_CS_N1 \B"
$PN"DY40"121;
"DDR6_SB_CS_N2 \B"
$PN"DU41"122;
"DDR6_SB_CS_N3 \B"
$PN"DV40"123;
"DDR6_SB_CA0"
$PN"DN43"124;
"DDR6_SB_CA1"
$PN"DP44"125;
"DDR6_SB_CA2"
$PN"DV44"126;
"DDR6_SB_CA3"
$PN"DY44"127;
"DDR6_SB_CA4"
$PN"DU43"128;
"DDR6_SB_CA5"
$PN"EA43"129;
"DDR6_SB_CA6"
$PN"DT42"130;
"DDR6_SA_PAR"
$PN"DL43"131;
"DDR6_SA_ECC0"
$PN"DL60"58;
"DDR6_SA_ECC1"
$PN"DK59"57;
"DDR6_SA_ECC2"
$PN"DN60"56;
"DDR6_SA_ECC3"
$PN"DP59"55;
"DDR6_SA_ECC4"
$PN"DK57"54;
"DDR6_SA_ECC5"
$PN"DL56"53;
"DDR6_SA_ECC6"
$PN"DP57"52;
"DDR6_SA_ECC7"
$PN"DN56"51;
"DDR6_SA_DQS_DP0"
$PN"DT73"132;
"DDR6_SA_DQS_DP1"
$PN"DL70"133;
"DDR6_SA_DQS_DP2"
$PN"DV61"134;
"DDR6_SA_DQS_DP3"
$PN"DJ64"135;
"DDR6_SA_DQS_DP4"
$PN"DJ58"136;
"DDR6_SA_DQS_DP5"
$PN"DY73"137;
"DDR6_SA_DQS_DP6"
$PN"DN70"138;
"DDR6_SA_DQS_DP7"
$PN"DY61"139;
"DDR6_SA_DQS_DP8"
$PN"DN64"140;
"DDR6_SA_DQS_DP9"
$PN"DN58"141;
"DDR6_SA_DQS_DN0 \B"
$PN"DV73"142;
"DDR6_SA_DQS_DN1 \B"
$PN"DJ70"143;
"DDR6_SA_DQS_DN2 \B"
$PN"DT61"144;
"DDR6_SA_DQS_DN3 \B"
$PN"DL64"145;
"DDR6_SA_DQS_DN4 \B"
$PN"DL58"146;
"DDR6_SA_DQS_DN5 \B"
$PN"EB73"147;
"DDR6_SA_DQS_DN6 \B"
$PN"DR70"148;
"DDR6_SA_DQS_DN7 \B"
$PN"EB61"149;
"DDR6_SA_DQS_DN8 \B"
$PN"DR64"150;
"DDR6_SA_DQS_DN9 \B"
$PN"DR58"151;
"DDR6_SA_DQ0"
$PN"DV75"50;
"DDR6_SA_DQ1"
$PN"DU74"49;
"DDR6_SA_DQ2"
$PN"DY75"48;
"DDR6_SA_DQ3"
$PN"EA74"47;
"DDR6_SA_DQ4"
$PN"DU72"46;
"DDR6_SA_DQ5"
$PN"DV71"45;
"DDR6_SA_DQ6"
$PN"EA72"44;
"DDR6_SA_DQ7"
$PN"DY71"43;
"DDR6_SA_DQ8"
$PN"DL72"42;
"DDR6_SA_DQ9"
$PN"DK71"41;
"DDR6_SA_DQ10"
$PN"DN72"40;
"DDR6_SA_DQ11"
$PN"DP71"39;
"DDR6_SA_DQ12"
$PN"DK69"38;
"DDR6_SA_DQ13"
$PN"DL68"37;
"DDR6_SA_DQ14"
$PN"DP69"36;
"DDR6_SA_DQ15"
$PN"DN68"35;
"DDR6_SA_DQ16"
$PN"DV63"34;
"DDR6_SA_DQ17"
$PN"DU62"33;
"DDR6_SA_DQ18"
$PN"DY63"32;
"DDR6_SA_DQ19"
$PN"EA62"31;
"DDR6_SA_DQ20"
$PN"DU60"30;
"DDR6_SA_DQ21"
$PN"DV59"29;
"DDR6_SA_DQ22"
$PN"EA60"28;
"DDR6_SA_DQ23"
$PN"DY59"27;
"DDR6_SA_DQ24"
$PN"DL66"26;
"DDR6_SA_DQ25"
$PN"DK65"25;
"DDR6_SA_DQ26"
$PN"DN66"24;
"DDR6_SA_DQ27"
$PN"DP65"23;
"DDR6_SA_DQ28"
$PN"DK63"22;
"DDR6_SA_DQ29"
$PN"DL62"21;
"DDR6_SA_DQ30"
$PN"DP63"20;
"DDR6_SA_DQ31"
$PN"DN62"19;
"DDR6_SA_CS_N0 \B"
$PN"DN54"152;
"DDR6_SA_CS_N1 \B"
$PN"DP53"153;
"DDR6_SA_CS_N2 \B"
$PN"DL54"154;
"DDR6_SA_CS_N3 \B"
$PN"DK53"155;
"DDR6_SA_CA0"
$PN"DJ52"156;
"DDR6_SA_CA1"
$PN"DR52"157;
"DDR6_SA_CA2"
$PN"DK51"158;
"DDR6_SA_CA3"
$PN"DP51"159;
"DDR6_SA_CA4"
$PN"DL50"160;
"DDR6_SA_CA5"
$PN"DN50"161;
"DDR6_SA_CA6"
$PN"DK44"162;
"DDR6_CLK_DP0"
$PN"DN45"18;
"DDR6_CLK_DP1"
$PN"DJ45"17;
"DDR6_CLK_DN0 \B"
$PN"DR45"15;
"DDR6_CLK_DN1 \B"
$PN"DL45"16;
"DDR6_B_RSP0"
$PN"DU48"163;
"DDR6_B_RSP1"
$PN"DV47"164;
"DDR6_A_RSP0"
$PN"EA48"165;
"DDR6_A_RSP1"
$PN"DY47"166;
"DDR6_ALERT_N \B"
$PN"CW50"167;
%"TAP"
"1","(-1200,500)","2","standard","I17";
;
CDS_LIB"standard"
BODY_TYPE"PLUMBING"
HDL_TAP"TRUE";
"B \NAC \NWC"10;
"S \NAC"
BN"0"90;
%"TAP"
"1","(-1200,550)","2","standard","I18";
;
CDS_LIB"standard"
BODY_TYPE"PLUMBING"
HDL_TAP"TRUE";
"B \NAC \NWC"10;
"S \NAC"
BN"1"89;
%"TAP"
"1","(-1200,600)","2","standard","I19";
;
CDS_LIB"standard"
BODY_TYPE"PLUMBING"
HDL_TAP"TRUE";
"B \NAC \NWC"10;
"S \NAC"
BN"2"88;
%"TAP"
"1","(-1200,700)","2","standard","I20";
;
CDS_LIB"standard"
BODY_TYPE"PLUMBING"
HDL_TAP"TRUE";
"B \NAC \NWC"10;
"S \NAC"
BN"4"86;
%"TAP"
"1","(-1200,650)","2","standard","I21";
;
CDS_LIB"standard"
BODY_TYPE"PLUMBING"
HDL_TAP"TRUE";
"B \NAC \NWC"10;
"S \NAC"
BN"3"87;
%"TAP"
"1","(-1200,750)","2","standard","I22";
;
CDS_LIB"standard"
BODY_TYPE"PLUMBING"
HDL_TAP"TRUE";
"B \NAC \NWC"10;
"S \NAC"
BN"5"85;
%"TAP"
"1","(-1200,800)","2","standard","I23";
;
CDS_LIB"standard"
BODY_TYPE"PLUMBING"
HDL_TAP"TRUE";
"B \NAC \NWC"10;
"S \NAC"
BN"6"84;
%"TAP"
"1","(-1200,850)","2","standard","I24";
;
CDS_LIB"standard"
BODY_TYPE"PLUMBING"
HDL_TAP"TRUE";
"B \NAC \NWC"10;
"S \NAC"
BN"7"83;
%"TAP"
"1","(-1200,950)","2","standard","I25";
;
CDS_LIB"standard"
BODY_TYPE"PLUMBING"
HDL_TAP"TRUE";
"B \NAC \NWC"10;
"S \NAC"
BN"9"81;
%"TAP"
"1","(-1200,900)","2","standard","I26";
;
CDS_LIB"standard"
BODY_TYPE"PLUMBING"
HDL_TAP"TRUE";
"B \NAC \NWC"10;
"S \NAC"
BN"8"82;
%"TAP"
"1","(-1200,1000)","2","standard","I27";
;
CDS_LIB"standard"
BODY_TYPE"PLUMBING"
HDL_TAP"TRUE";
"B \NAC \NWC"10;
"S \NAC"
BN"10"80;
%"TAP"
"1","(-1200,1050)","2","standard","I28";
;
CDS_LIB"standard"
BODY_TYPE"PLUMBING"
HDL_TAP"TRUE";
"B \NAC \NWC"10;
"S \NAC"
BN"11"79;
%"TAP"
"1","(-1200,1100)","2","standard","I29";
;
CDS_LIB"standard"
BODY_TYPE"PLUMBING"
HDL_TAP"TRUE";
"B \NAC \NWC"10;
"S \NAC"
BN"12"78;
%"TAP"
"1","(-1200,-150)","2","standard","I3";
;
CDS_LIB"standard"
BODY_TYPE"PLUMBING"
HDL_TAP"TRUE";
"B \NAC \NWC"14;
"S \NAC"
BN"0"15;
%"TAP"
"1","(-1200,1150)","2","standard","I30";
;
CDS_LIB"standard"
BODY_TYPE"PLUMBING"
HDL_TAP"TRUE";
"B \NAC \NWC"10;
"S \NAC"
BN"13"77;
%"TAP"
"1","(-1200,1200)","2","standard","I31";
;
CDS_LIB"standard"
BODY_TYPE"PLUMBING"
HDL_TAP"TRUE";
"B \NAC \NWC"10;
"S \NAC"
BN"14"76;
%"TAP"
"1","(-1200,1250)","2","standard","I32";
;
CDS_LIB"standard"
BODY_TYPE"PLUMBING"
HDL_TAP"TRUE";
"B \NAC \NWC"10;
"S \NAC"
BN"15"75;
%"TAP"
"1","(-1200,1300)","2","standard","I33";
;
CDS_LIB"standard"
BODY_TYPE"PLUMBING"
HDL_TAP"TRUE";
"B \NAC \NWC"10;
"S \NAC"
BN"16"74;
%"TAP"
"1","(-1200,1350)","2","standard","I34";
;
CDS_LIB"standard"
BODY_TYPE"PLUMBING"
HDL_TAP"TRUE";
"B \NAC \NWC"10;
"S \NAC"
BN"17"73;
%"TAP"
"1","(-1200,1400)","2","standard","I35";
;
CDS_LIB"standard"
BODY_TYPE"PLUMBING"
HDL_TAP"TRUE";
"B \NAC \NWC"10;
"S \NAC"
BN"18"72;
%"TAP"
"1","(-1200,1450)","2","standard","I36";
;
CDS_LIB"standard"
BODY_TYPE"PLUMBING"
HDL_TAP"TRUE";
"B \NAC \NWC"10;
"S \NAC"
BN"19"71;
%"TAP"
"1","(-1200,1500)","2","standard","I37";
;
CDS_LIB"standard"
BODY_TYPE"PLUMBING"
HDL_TAP"TRUE";
"B \NAC \NWC"10;
"S \NAC"
BN"20"70;
%"TAP"
"1","(-1200,1550)","2","standard","I38";
;
CDS_LIB"standard"
BODY_TYPE"PLUMBING"
HDL_TAP"TRUE";
"B \NAC \NWC"10;
"S \NAC"
BN"21"69;
%"TAP"
"1","(-1200,1600)","2","standard","I39";
;
CDS_LIB"standard"
BODY_TYPE"PLUMBING"
HDL_TAP"TRUE";
"B \NAC \NWC"10;
"S \NAC"
BN"22"68;
%"TAP"
"1","(-1200,-100)","2","standard","I4";
;
CDS_LIB"standard"
BODY_TYPE"PLUMBING"
HDL_TAP"TRUE";
"B \NAC \NWC"14;
"S \NAC"
BN"1"16;
%"TAP"
"1","(-1200,1650)","2","standard","I40";
;
CDS_LIB"standard"
BODY_TYPE"PLUMBING"
HDL_TAP"TRUE";
"B \NAC \NWC"10;
"S \NAC"
BN"23"67;
%"TAP"
"1","(-1200,1700)","2","standard","I41";
;
CDS_LIB"standard"
BODY_TYPE"PLUMBING"
HDL_TAP"TRUE";
"B \NAC \NWC"10;
"S \NAC"
BN"24"66;
%"TAP"
"1","(-1200,1750)","2","standard","I42";
;
CDS_LIB"standard"
BODY_TYPE"PLUMBING"
HDL_TAP"TRUE";
"B \NAC \NWC"10;
"S \NAC"
BN"25"65;
%"TAP"
"1","(-1200,1850)","2","standard","I43";
;
CDS_LIB"standard"
BODY_TYPE"PLUMBING"
HDL_TAP"TRUE";
"B \NAC \NWC"10;
"S \NAC"
BN"27"63;
%"TAP"
"1","(-1200,1800)","2","standard","I44";
;
CDS_LIB"standard"
BODY_TYPE"PLUMBING"
HDL_TAP"TRUE";
"B \NAC \NWC"10;
"S \NAC"
BN"26"64;
%"TAP"
"1","(-1200,1900)","2","standard","I45";
;
CDS_LIB"standard"
BODY_TYPE"PLUMBING"
HDL_TAP"TRUE";
"B \NAC \NWC"10;
"S \NAC"
BN"28"62;
%"TAP"
"1","(-1200,1950)","2","standard","I46";
;
CDS_LIB"standard"
BODY_TYPE"PLUMBING"
HDL_TAP"TRUE";
"B \NAC \NWC"10;
"S \NAC"
BN"29"61;
%"TAP"
"1","(-1200,2000)","2","standard","I47";
;
CDS_LIB"standard"
BODY_TYPE"PLUMBING"
HDL_TAP"TRUE";
"B \NAC \NWC"10;
"S \NAC"
BN"30"60;
%"TAP"
"1","(-1200,-50)","2","standard","I5";
;
CDS_LIB"standard"
BODY_TYPE"PLUMBING"
HDL_TAP"TRUE";
"B \NAC \NWC"13;
"S \NAC"
BN"0"18;
%"TAP"
"1","(-1200,2100)","2","standard","I50";
;
CDS_LIB"standard"
BODY_TYPE"PLUMBING"
HDL_TAP"TRUE";
"B \NAC \NWC"11;
"S \NAC"
BN"0"58;
%"TAP"
"1","(-1200,2050)","2","standard","I51";
;
CDS_LIB"standard"
BODY_TYPE"PLUMBING"
HDL_TAP"TRUE";
"B \NAC \NWC"10;
"S \NAC"
BN"31"59;
%"TAP"
"1","(-1200,2150)","2","standard","I52";
;
CDS_LIB"standard"
BODY_TYPE"PLUMBING"
HDL_TAP"TRUE";
"B \NAC \NWC"11;
"S \NAC"
BN"1"57;
%"TAP"
"1","(-1200,2200)","2","standard","I53";
;
CDS_LIB"standard"
BODY_TYPE"PLUMBING"
HDL_TAP"TRUE";
"B \NAC \NWC"11;
"S \NAC"
BN"2"56;
%"TAP"
"1","(-1200,2250)","2","standard","I54";
;
CDS_LIB"standard"
BODY_TYPE"PLUMBING"
HDL_TAP"TRUE";
"B \NAC \NWC"11;
"S \NAC"
BN"3"55;
%"TAP"
"1","(-1200,2300)","2","standard","I55";
;
CDS_LIB"standard"
BODY_TYPE"PLUMBING"
HDL_TAP"TRUE";
"B \NAC \NWC"11;
"S \NAC"
BN"4"54;
%"TAP"
"1","(-1200,2350)","2","standard","I56";
;
CDS_LIB"standard"
BODY_TYPE"PLUMBING"
HDL_TAP"TRUE";
"B \NAC \NWC"11;
"S \NAC"
BN"5"53;
%"TAP"
"1","(-1200,2400)","2","standard","I57";
;
CDS_LIB"standard"
BODY_TYPE"PLUMBING"
HDL_TAP"TRUE";
"B \NAC \NWC"11;
"S \NAC"
BN"6"52;
%"TAP"
"1","(-1200,2450)","2","standard","I58";
;
CDS_LIB"standard"
BODY_TYPE"PLUMBING"
HDL_TAP"TRUE";
"B \NAC \NWC"11;
"S \NAC"
BN"7"51;
%"TAP"
"1","(-1200,2550)","2","standard","I59";
;
CDS_LIB"standard"
BODY_TYPE"PLUMBING"
HDL_TAP"TRUE";
"B \NAC \NWC"12;
"S \NAC"
BN"1"49;
%"TAP"
"1","(-1200,0)","2","standard","I6";
;
CDS_LIB"standard"
BODY_TYPE"PLUMBING"
HDL_TAP"TRUE";
"B \NAC \NWC"13;
"S \NAC"
BN"1"17;
%"TAP"
"1","(-1200,2500)","2","standard","I60";
;
CDS_LIB"standard"
BODY_TYPE"PLUMBING"
HDL_TAP"TRUE";
"B \NAC \NWC"12;
"S \NAC"
BN"0"50;
%"TAP"
"1","(-1200,2600)","2","standard","I61";
;
CDS_LIB"standard"
BODY_TYPE"PLUMBING"
HDL_TAP"TRUE";
"B \NAC \NWC"12;
"S \NAC"
BN"2"48;
%"TAP"
"1","(-1200,2650)","2","standard","I62";
;
CDS_LIB"standard"
BODY_TYPE"PLUMBING"
HDL_TAP"TRUE";
"B \NAC \NWC"12;
"S \NAC"
BN"3"47;
%"TAP"
"1","(-1200,2750)","2","standard","I63";
;
CDS_LIB"standard"
BODY_TYPE"PLUMBING"
HDL_TAP"TRUE";
"B \NAC \NWC"12;
"S \NAC"
BN"5"45;
%"TAP"
"1","(-1200,2700)","2","standard","I64";
;
CDS_LIB"standard"
BODY_TYPE"PLUMBING"
HDL_TAP"TRUE";
"B \NAC \NWC"12;
"S \NAC"
BN"4"46;
%"TAP"
"1","(-1200,2800)","2","standard","I65";
;
CDS_LIB"standard"
BODY_TYPE"PLUMBING"
HDL_TAP"TRUE";
"B \NAC \NWC"12;
"S \NAC"
BN"6"44;
%"TAP"
"1","(-1200,2850)","2","standard","I66";
;
CDS_LIB"standard"
BODY_TYPE"PLUMBING"
HDL_TAP"TRUE";
"B \NAC \NWC"12;
"S \NAC"
BN"7"43;
%"TAP"
"1","(-1200,2900)","2","standard","I67";
;
CDS_LIB"standard"
BODY_TYPE"PLUMBING"
HDL_TAP"TRUE";
"B \NAC \NWC"12;
"S \NAC"
BN"8"42;
%"TAP"
"1","(-1200,3000)","2","standard","I68";
;
CDS_LIB"standard"
BODY_TYPE"PLUMBING"
HDL_TAP"TRUE";
"B \NAC \NWC"12;
"S \NAC"
BN"10"40;
%"TAP"
"1","(-1200,2950)","2","standard","I69";
;
CDS_LIB"standard"
BODY_TYPE"PLUMBING"
HDL_TAP"TRUE";
"B \NAC \NWC"12;
"S \NAC"
BN"9"41;
%"TAP"
"1","(-1200,3050)","2","standard","I70";
;
CDS_LIB"standard"
BODY_TYPE"PLUMBING"
HDL_TAP"TRUE";
"B \NAC \NWC"12;
"S \NAC"
BN"11"39;
%"TAP"
"1","(-1200,3100)","2","standard","I71";
;
CDS_LIB"standard"
BODY_TYPE"PLUMBING"
HDL_TAP"TRUE";
"B \NAC \NWC"12;
"S \NAC"
BN"12"38;
%"TAP"
"1","(-1200,3150)","2","standard","I72";
;
CDS_LIB"standard"
BODY_TYPE"PLUMBING"
HDL_TAP"TRUE";
"B \NAC \NWC"12;
"S \NAC"
BN"13"37;
%"TAP"
"1","(-1200,3200)","2","standard","I73";
;
CDS_LIB"standard"
BODY_TYPE"PLUMBING"
HDL_TAP"TRUE";
"B \NAC \NWC"12;
"S \NAC"
BN"14"36;
%"TAP"
"1","(-1200,3250)","2","standard","I74";
;
CDS_LIB"standard"
BODY_TYPE"PLUMBING"
HDL_TAP"TRUE";
"B \NAC \NWC"12;
"S \NAC"
BN"15"35;
%"TAP"
"1","(-1200,3300)","2","standard","I75";
;
CDS_LIB"standard"
BODY_TYPE"PLUMBING"
HDL_TAP"TRUE";
"B \NAC \NWC"12;
"S \NAC"
BN"16"34;
%"TAP"
"1","(-1200,3350)","2","standard","I76";
;
CDS_LIB"standard"
BODY_TYPE"PLUMBING"
HDL_TAP"TRUE";
"B \NAC \NWC"12;
"S \NAC"
BN"17"33;
%"TAP"
"1","(-1200,3400)","2","standard","I77";
;
CDS_LIB"standard"
BODY_TYPE"PLUMBING"
HDL_TAP"TRUE";
"B \NAC \NWC"12;
"S \NAC"
BN"18"32;
%"TAP"
"1","(-1200,3450)","2","standard","I78";
;
CDS_LIB"standard"
BODY_TYPE"PLUMBING"
HDL_TAP"TRUE";
"B \NAC \NWC"12;
"S \NAC"
BN"19"31;
%"TAP"
"1","(-1200,3500)","2","standard","I79";
;
CDS_LIB"standard"
BODY_TYPE"PLUMBING"
HDL_TAP"TRUE";
"B \NAC \NWC"12;
"S \NAC"
BN"20"30;
%"TAP"
"1","(-1200,3550)","2","standard","I80";
;
CDS_LIB"standard"
BODY_TYPE"PLUMBING"
HDL_TAP"TRUE";
"B \NAC \NWC"12;
"S \NAC"
BN"21"29;
%"TAP"
"1","(-1200,3600)","2","standard","I81";
;
CDS_LIB"standard"
BODY_TYPE"PLUMBING"
HDL_TAP"TRUE";
"B \NAC \NWC"12;
"S \NAC"
BN"22"28;
%"TAP"
"1","(-1200,3650)","2","standard","I82";
;
CDS_LIB"standard"
BODY_TYPE"PLUMBING"
HDL_TAP"TRUE";
"B \NAC \NWC"12;
"S \NAC"
BN"23"27;
%"TAP"
"1","(-1200,3700)","2","standard","I83";
;
CDS_LIB"standard"
BODY_TYPE"PLUMBING"
HDL_TAP"TRUE";
"B \NAC \NWC"12;
"S \NAC"
BN"24"26;
%"TAP"
"1","(-1200,3750)","2","standard","I84";
;
CDS_LIB"standard"
BODY_TYPE"PLUMBING"
HDL_TAP"TRUE";
"B \NAC \NWC"12;
"S \NAC"
BN"25"25;
%"TAP"
"1","(-1200,3800)","2","standard","I85";
;
CDS_LIB"standard"
BODY_TYPE"PLUMBING"
HDL_TAP"TRUE";
"B \NAC \NWC"12;
"S \NAC"
BN"26"24;
%"TAP"
"1","(-1200,3900)","2","standard","I86";
;
CDS_LIB"standard"
BODY_TYPE"PLUMBING"
HDL_TAP"TRUE";
"B \NAC \NWC"12;
"S \NAC"
BN"28"22;
%"TAP"
"1","(-1200,3850)","2","standard","I87";
;
CDS_LIB"standard"
BODY_TYPE"PLUMBING"
HDL_TAP"TRUE";
"B \NAC \NWC"12;
"S \NAC"
BN"27"23;
%"TAP"
"1","(-1200,3950)","2","standard","I88";
;
CDS_LIB"standard"
BODY_TYPE"PLUMBING"
HDL_TAP"TRUE";
"B \NAC \NWC"12;
"S \NAC"
BN"29"21;
%"TAP"
"1","(-1200,4000)","2","standard","I89";
;
CDS_LIB"standard"
BODY_TYPE"PLUMBING"
HDL_TAP"TRUE";
"B \NAC \NWC"12;
"S \NAC"
BN"30"20;
%"TAP"
"1","(-1200,100)","2","standard","I9";
;
CDS_LIB"standard"
BODY_TYPE"PLUMBING"
HDL_TAP"TRUE";
"B \NAC \NWC"9;
"S \NAC"
BN"0"98;
%"TAP"
"1","(-1200,4050)","2","standard","I90";
;
CDS_LIB"standard"
BODY_TYPE"PLUMBING"
HDL_TAP"TRUE";
"B \NAC \NWC"12;
"S \NAC"
BN"31"19;
%"TAP"
"1","(2225,450)","0","standard","I94";
;
CDS_LIB"standard"
BODY_TYPE"PLUMBING"
HDL_TAP"TRUE";
"B \NAC \NWC"6;
"S \NAC"
BN"3"123;
%"TAP"
"1","(2225,350)","0","standard","I95";
;
CDS_LIB"standard"
BODY_TYPE"PLUMBING"
HDL_TAP"TRUE";
"B \NAC \NWC"6;
"S \NAC"
BN"1"121;
%"TAP"
"1","(2225,300)","0","standard","I96";
;
CDS_LIB"standard"
BODY_TYPE"PLUMBING"
HDL_TAP"TRUE";
"B \NAC \NWC"6;
"S \NAC"
BN"0"120;
%"TAP"
"1","(2225,400)","0","standard","I97";
;
CDS_LIB"standard"
BODY_TYPE"PLUMBING"
HDL_TAP"TRUE";
"B \NAC \NWC"6;
"S \NAC"
BN"2"122;
%"TAP"
"1","(2225,700)","0","standard","I98";
;
CDS_LIB"standard"
BODY_TYPE"PLUMBING"
HDL_TAP"TRUE";
"B \NAC \NWC"2;
"S \NAC"
BN"2"154;
%"TAP"
"1","(2225,600)","0","standard","I99";
;
CDS_LIB"standard"
BODY_TYPE"PLUMBING"
HDL_TAP"TRUE";
"B \NAC \NWC"2;
"S \NAC"
BN"0"152;
END.
